(kicad_pcb
	(version 20260206)
	(generator "pcbnew")
	(generator_version "10.0")
	(general
		(thickness 1.6)
		(legacy_teardrops no)
	)
	(paper "A4")
	(title_block
		(title "04192023_DAF0TMB3IC0_F0TG_MB_C_brd_V02_OCP.brd")
		(comment 1 "Grand Teton / footprints 8044-8050 of 8354")
	)
	(layers
		(0 "F.Cu" signal "TOP")
		(4 "In1.Cu" signal "GND")
		(6 "In2.Cu" signal "IN1")
		(8 "In3.Cu" signal "GND1")
		(10 "In4.Cu" signal "IN2")
		(12 "In5.Cu" signal "GND2")
		(14 "In6.Cu" signal "IN3")
		(16 "In7.Cu" signal "GND3")
		(18 "In8.Cu" signal "VCC")
		(20 "In9.Cu" signal "VCC1")
		(22 "In10.Cu" signal "GND4")
		(24 "In11.Cu" signal "IN4")
		(26 "In12.Cu" signal "GND5")
		(28 "In13.Cu" signal "IN5")
		(30 "In14.Cu" signal "GND6")
		(32 "In15.Cu" signal "IN6")
		(34 "In16.Cu" signal "GND7")
		(2 "B.Cu" signal "BOTTOM")
		(9 "F.Adhes" user "F.Adhesive")
		(11 "B.Adhes" user "B.Adhesive")
		(13 "F.Paste" user "Package Geometry/Pastemask Top")
		(15 "B.Paste" user "Package Geometry/Pastemask Bottom")
		(5 "F.SilkS" user "Ref Des/Silkscreen Top")
		(7 "B.SilkS" user "Ref Des/Silkscreen Bottom")
		(1 "F.Mask" user "Board Geometry/Soldermask Top")
		(3 "B.Mask" user "Board Geometry/Soldermask Bottom")
		(17 "Dwgs.User" user "User.Drawings")
		(19 "Cmts.User" user "User.Comments")
		(21 "Eco1.User" user "User.Eco1")
		(23 "Eco2.User" user "User.Eco2")
		(25 "Edge.Cuts" user "Board Geometry/Outline")
		(27 "Margin" user)
		(31 "F.CrtYd" user "Package Geometry/Place Bound Top")
		(29 "B.CrtYd" user "Package Geometry/Place Bound Bottom")
		(35 "F.Fab" user "Ref Des/Assembly Top")
		(33 "B.Fab" user "Ref Des/Assembly Bottom")
	)
	(footprint ""
		(layer "B.Cu")
		(at 321.100958 -203.917296 -90)
		(property "Reference" "R387"
			(at 0 0 90)
			(layer "B.SilkS")
			(hide yes)
			(effects
				(font
					(size 1.27 1.27)
				)
				(justify mirror)
			)
		)
		(property "Value" ""
			(at 0 0 90)
			(layer "B.Fab")
			(effects
				(font
					(size 1.27 1.27)
				)
				(justify mirror)
			)
		)
		(duplicate_pad_numbers_are_jumpers no)
		(fp_line
			(start -0.7874 0.4064)
			(end 0.7874 0.4064)
			(stroke
				(width 0.1524)
				(type default)
			)
			(layer "B.SilkS")
		)
		(fp_line
			(start 0.7874 0.4064)
			(end 0.7874 -0.4064)
			(stroke
				(width 0.1524)
				(type default)
			)
			(layer "B.SilkS")
		)
		(fp_line
			(start -0.7874 -0.4064)
			(end -0.7874 0.4064)
			(stroke
				(width 0.1524)
				(type default)
			)
			(layer "B.SilkS")
		)
		(fp_line
			(start 0.7874 -0.4064)
			(end -0.7874 -0.4064)
			(stroke
				(width 0.1524)
				(type default)
			)
			(layer "B.SilkS")
		)
		(fp_line
			(start -0.67945 0.3048)
			(end -0.120396 0.3048)
			(stroke
				(width 0.1)
				(type default)
			)
			(layer "B.Fab")
		)
		(fp_line
			(start -0.120396 0.3048)
			(end -0.120396 0.2794)
			(stroke
				(width 0.1)
				(type default)
			)
			(layer "B.Fab")
		)
		(fp_line
			(start 0.12065 0.3048)
			(end 0.67945 0.3048)
			(stroke
				(width 0.1)
				(type default)
			)
			(layer "B.Fab")
		)
		(fp_line
			(start 0.67945 0.3048)
			(end 0.67945 -0.305054)
			(stroke
				(width 0.1)
				(type default)
			)
			(layer "B.Fab")
		)
		(fp_line
			(start -0.120396 0.2794)
			(end 0.12065 0.2794)
			(stroke
				(width 0.1)
				(type default)
			)
			(layer "B.Fab")
		)
		(fp_line
			(start 0.12065 0.2794)
			(end 0.12065 0.3048)
			(stroke
				(width 0.1)
				(type default)
			)
			(layer "B.Fab")
		)
		(fp_line
			(start -0.12065 -0.2794)
			(end -0.12065 -0.3048)
			(stroke
				(width 0.1)
				(type default)
			)
			(layer "B.Fab")
		)
		(fp_line
			(start 0.12065 -0.2794)
			(end -0.12065 -0.2794)
			(stroke
				(width 0.1)
				(type default)
			)
			(layer "B.Fab")
		)
		(fp_line
			(start -0.67945 -0.3048)
			(end -0.67945 0.3048)
			(stroke
				(width 0.1)
				(type default)
			)
			(layer "B.Fab")
		)
		(fp_line
			(start -0.12065 -0.3048)
			(end -0.67945 -0.3048)
			(stroke
				(width 0.1)
				(type default)
			)
			(layer "B.Fab")
		)
		(fp_line
			(start 0.12065 -0.305054)
			(end 0.12065 -0.2794)
			(stroke
				(width 0.1)
				(type default)
			)
			(layer "B.Fab")
		)
		(fp_line
			(start 0.67945 -0.305054)
			(end 0.12065 -0.305054)
			(stroke
				(width 0.1)
				(type default)
			)
			(layer "B.Fab")
		)
		(pad "1" smd circle
			(at 0.40005 0 90)
			(size 0 0)
			(layers "B.Cu" "B.Mask" "B.Paste")
			(net "P3V3_AUX")
		)
		(pad "2" smd circle
			(at -0.40005 0 90)
			(size 0 0)
			(layers "B.Cu" "B.Mask" "B.Paste")
			(net "CPU0_CORETYPE2")
		)
	)
	(footprint ""
		(layer "B.Cu")
		(at 100.271834 -261.947152)
		(property "Reference" "C2106"
			(at 0 0 0)
			(layer "B.SilkS")
			(hide yes)
			(effects
				(font
					(size 1.27 1.27)
				)
				(justify mirror)
			)
		)
		(property "Value" ""
			(at 0 0 0)
			(layer "B.Fab")
			(effects
				(font
					(size 1.27 1.27)
				)
				(justify mirror)
			)
		)
		(duplicate_pad_numbers_are_jumpers no)
		(fp_line
			(start -0.7874 -0.4064)
			(end -0.7874 0.4064)
			(stroke
				(width 0.1524)
				(type default)
			)
			(layer "B.SilkS")
		)
		(fp_line
			(start -0.7874 0.4064)
			(end 0.7874 0.4064)
			(stroke
				(width 0.1524)
				(type default)
			)
			(layer "B.SilkS")
		)
		(fp_line
			(start 0.7874 -0.4064)
			(end -0.7874 -0.4064)
			(stroke
				(width 0.1524)
				(type default)
			)
			(layer "B.SilkS")
		)
		(fp_line
			(start 0.7874 0.4064)
			(end 0.7874 -0.4064)
			(stroke
				(width 0.1524)
				(type default)
			)
			(layer "B.SilkS")
		)
		(fp_line
			(start -0.67945 -0.3048)
			(end -0.67945 0.3048)
			(stroke
				(width 0.1)
				(type default)
			)
			(layer "B.Fab")
		)
		(fp_line
			(start -0.67945 0.3048)
			(end -0.120396 0.3048)
			(stroke
				(width 0.1)
				(type default)
			)
			(layer "B.Fab")
		)
		(fp_line
			(start -0.12065 -0.3048)
			(end -0.67945 -0.3048)
			(stroke
				(width 0.1)
				(type default)
			)
			(layer "B.Fab")
		)
		(fp_line
			(start -0.12065 -0.2794)
			(end -0.12065 -0.3048)
			(stroke
				(width 0.1)
				(type default)
			)
			(layer "B.Fab")
		)
		(fp_line
			(start -0.120396 0.2794)
			(end 0.12065 0.2794)
			(stroke
				(width 0.1)
				(type default)
			)
			(layer "B.Fab")
		)
		(fp_line
			(start -0.120396 0.3048)
			(end -0.120396 0.2794)
			(stroke
				(width 0.1)
				(type default)
			)
			(layer "B.Fab")
		)
		(fp_line
			(start 0.12065 -0.305054)
			(end 0.12065 -0.2794)
			(stroke
				(width 0.1)
				(type default)
			)
			(layer "B.Fab")
		)
		(fp_line
			(start 0.12065 -0.2794)
			(end -0.12065 -0.2794)
			(stroke
				(width 0.1)
				(type default)
			)
			(layer "B.Fab")
		)
		(fp_line
			(start 0.12065 0.2794)
			(end 0.12065 0.3048)
			(stroke
				(width 0.1)
				(type default)
			)
			(layer "B.Fab")
		)
		(fp_line
			(start 0.12065 0.3048)
			(end 0.67945 0.3048)
			(stroke
				(width 0.1)
				(type default)
			)
			(layer "B.Fab")
		)
		(fp_line
			(start 0.67945 -0.305054)
			(end 0.12065 -0.305054)
			(stroke
				(width 0.1)
				(type default)
			)
			(layer "B.Fab")
		)
		(fp_line
			(start 0.67945 0.3048)
			(end 0.67945 -0.305054)
			(stroke
				(width 0.1)
				(type default)
			)
			(layer "B.Fab")
		)
		(pad "1" smd circle
			(at 0.40005 0 180)
			(size 0 0)
			(layers "B.Cu" "B.Mask" "B.Paste")
			(net "PVDDIO_P1")
		)
		(pad "2" smd circle
			(at -0.40005 0 180)
			(size 0 0)
			(layers "B.Cu" "B.Mask" "B.Paste")
			(net "GND")
		)
	)
	(footprint ""
		(layer "B.Cu")
		(at 237.692692 -422.849548 90)
		(property "Reference" "R2906"
			(at 0 0 90)
			(layer "B.SilkS")
			(hide yes)
			(effects
				(font
					(size 1.27 1.27)
				)
				(justify mirror)
			)
		)
		(property "Value" ""
			(at 0 0 90)
			(layer "B.Fab")
			(effects
				(font
					(size 1.27 1.27)
				)
				(justify mirror)
			)
		)
		(duplicate_pad_numbers_are_jumpers no)
		(fp_line
			(start 0.7874 -0.4064)
			(end -0.7874 -0.4064)
			(stroke
				(width 0.1524)
				(type default)
			)
			(layer "B.SilkS")
		)
		(fp_line
			(start -0.7874 -0.4064)
			(end -0.7874 0.4064)
			(stroke
				(width 0.1524)
				(type default)
			)
			(layer "B.SilkS")
		)
		(fp_line
			(start 0.7874 0.4064)
			(end 0.7874 -0.4064)
			(stroke
				(width 0.1524)
				(type default)
			)
			(layer "B.SilkS")
		)
		(fp_line
			(start -0.7874 0.4064)
			(end 0.7874 0.4064)
			(stroke
				(width 0.1524)
				(type default)
			)
			(layer "B.SilkS")
		)
		(fp_line
			(start 0.67945 -0.305054)
			(end 0.12065 -0.305054)
			(stroke
				(width 0.1)
				(type default)
			)
			(layer "B.Fab")
		)
		(fp_line
			(start 0.12065 -0.305054)
			(end 0.12065 -0.2794)
			(stroke
				(width 0.1)
				(type default)
			)
			(layer "B.Fab")
		)
		(fp_line
			(start -0.12065 -0.3048)
			(end -0.67945 -0.3048)
			(stroke
				(width 0.1)
				(type default)
			)
			(layer "B.Fab")
		)
		(fp_line
			(start -0.67945 -0.3048)
			(end -0.67945 0.3048)
			(stroke
				(width 0.1)
				(type default)
			)
			(layer "B.Fab")
		)
		(fp_line
			(start 0.12065 -0.2794)
			(end -0.12065 -0.2794)
			(stroke
				(width 0.1)
				(type default)
			)
			(layer "B.Fab")
		)
		(fp_line
			(start -0.12065 -0.2794)
			(end -0.12065 -0.3048)
			(stroke
				(width 0.1)
				(type default)
			)
			(layer "B.Fab")
		)
		(fp_line
			(start 0.12065 0.2794)
			(end 0.12065 0.3048)
			(stroke
				(width 0.1)
				(type default)
			)
			(layer "B.Fab")
		)
		(fp_line
			(start -0.120396 0.2794)
			(end 0.12065 0.2794)
			(stroke
				(width 0.1)
				(type default)
			)
			(layer "B.Fab")
		)
		(fp_line
			(start 0.67945 0.3048)
			(end 0.67945 -0.305054)
			(stroke
				(width 0.1)
				(type default)
			)
			(layer "B.Fab")
		)
		(fp_line
			(start 0.12065 0.3048)
			(end 0.67945 0.3048)
			(stroke
				(width 0.1)
				(type default)
			)
			(layer "B.Fab")
		)
		(fp_line
			(start -0.120396 0.3048)
			(end -0.120396 0.2794)
			(stroke
				(width 0.1)
				(type default)
			)
			(layer "B.Fab")
		)
		(fp_line
			(start -0.67945 0.3048)
			(end -0.120396 0.3048)
			(stroke
				(width 0.1)
				(type default)
			)
			(layer "B.Fab")
		)
		(pad "1" smd circle
			(at 0.40005 0 270)
			(size 0 0)
			(layers "B.Cu" "B.Mask" "B.Paste")
			(net "FM_GPU_HSC_EN_BUF_R1")
		)
		(pad "2" smd circle
			(at -0.40005 0 270)
			(size 0 0)
			(layers "B.Cu" "B.Mask" "B.Paste")
			(net "FM_GPU_HSC_EN_BUF")
		)
	)
	(footprint ""
		(layer "B.Cu")
		(at 22.479 -358.775 180)
		(property "Reference" "R8220"
			(at 0 0 0)
			(layer "B.SilkS")
			(hide yes)
			(effects
				(font
					(size 1.27 1.27)
				)
				(justify mirror)
			)
		)
		(property "Value" ""
			(at 0 0 0)
			(layer "B.Fab")
			(effects
				(font
					(size 1.27 1.27)
				)
				(justify mirror)
			)
		)
		(duplicate_pad_numbers_are_jumpers no)
		(fp_line
			(start 0.7874 0.4064)
			(end 0.7874 -0.4064)
			(stroke
				(width 0.1524)
				(type default)
			)
			(layer "B.SilkS")
		)
		(fp_line
			(start 0.7874 -0.4064)
			(end -0.7874 -0.4064)
			(stroke
				(width 0.1524)
				(type default)
			)
			(layer "B.SilkS")
		)
		(fp_line
			(start -0.7874 0.4064)
			(end 0.7874 0.4064)
			(stroke
				(width 0.1524)
				(type default)
			)
			(layer "B.SilkS")
		)
		(fp_line
			(start -0.7874 -0.4064)
			(end -0.7874 0.4064)
			(stroke
				(width 0.1524)
				(type default)
			)
			(layer "B.SilkS")
		)
		(fp_line
			(start 0.67945 0.3048)
			(end 0.67945 -0.305054)
			(stroke
				(width 0.1)
				(type default)
			)
			(layer "B.Fab")
		)
		(fp_line
			(start 0.67945 -0.305054)
			(end 0.12065 -0.305054)
			(stroke
				(width 0.1)
				(type default)
			)
			(layer "B.Fab")
		)
		(fp_line
			(start 0.12065 0.3048)
			(end 0.67945 0.3048)
			(stroke
				(width 0.1)
				(type default)
			)
			(layer "B.Fab")
		)
		(fp_line
			(start 0.12065 0.2794)
			(end 0.12065 0.3048)
			(stroke
				(width 0.1)
				(type default)
			)
			(layer "B.Fab")
		)
		(fp_line
			(start 0.12065 -0.2794)
			(end -0.12065 -0.2794)
			(stroke
				(width 0.1)
				(type default)
			)
			(layer "B.Fab")
		)
		(fp_line
			(start 0.12065 -0.305054)
			(end 0.12065 -0.2794)
			(stroke
				(width 0.1)
				(type default)
			)
			(layer "B.Fab")
		)
		(fp_line
			(start -0.120396 0.3048)
			(end -0.120396 0.2794)
			(stroke
				(width 0.1)
				(type default)
			)
			(layer "B.Fab")
		)
		(fp_line
			(start -0.120396 0.2794)
			(end 0.12065 0.2794)
			(stroke
				(width 0.1)
				(type default)
			)
			(layer "B.Fab")
		)
		(fp_line
			(start -0.12065 -0.2794)
			(end -0.12065 -0.3048)
			(stroke
				(width 0.1)
				(type default)
			)
			(layer "B.Fab")
		)
		(fp_line
			(start -0.12065 -0.3048)
			(end -0.67945 -0.3048)
			(stroke
				(width 0.1)
				(type default)
			)
			(layer "B.Fab")
		)
		(fp_line
			(start -0.67945 0.3048)
			(end -0.120396 0.3048)
			(stroke
				(width 0.1)
				(type default)
			)
			(layer "B.Fab")
		)
		(fp_line
			(start -0.67945 -0.3048)
			(end -0.67945 0.3048)
			(stroke
				(width 0.1)
				(type default)
			)
			(layer "B.Fab")
		)
		(pad "1" smd circle
			(at 0.40005 0)
			(size 0 0)
			(layers "B.Cu" "B.Mask" "B.Paste")
			(net "PVDD18_S5_P1")
		)
		(pad "2" smd circle
			(at -0.40005 0)
			(size 0 0)
			(layers "B.Cu" "B.Mask" "B.Paste")
			(net "SVID_PVDDCR_CPU1_P1_SVTO")
		)
	)
	(footprint ""
		(layer "B.Cu")
		(at 63.194438 -28.382722)
		(property "Reference" "R1196"
			(at 0 0 0)
			(layer "B.SilkS")
			(hide yes)
			(effects
				(font
					(size 1.27 1.27)
				)
				(justify mirror)
			)
		)
		(property "Value" ""
			(at 0 0 0)
			(layer "B.Fab")
			(effects
				(font
					(size 1.27 1.27)
				)
				(justify mirror)
			)
		)
		(duplicate_pad_numbers_are_jumpers no)
		(fp_line
			(start -0.7874 -0.4064)
			(end -0.7874 0.4064)
			(stroke
				(width 0.1524)
				(type default)
			)
			(layer "B.SilkS")
		)
		(fp_line
			(start -0.7874 0.4064)
			(end 0.7874 0.4064)
			(stroke
				(width 0.1524)
				(type default)
			)
			(layer "B.SilkS")
		)
		(fp_line
			(start 0.7874 -0.4064)
			(end -0.7874 -0.4064)
			(stroke
				(width 0.1524)
				(type default)
			)
			(layer "B.SilkS")
		)
		(fp_line
			(start 0.7874 0.4064)
			(end 0.7874 -0.4064)
			(stroke
				(width 0.1524)
				(type default)
			)
			(layer "B.SilkS")
		)
		(fp_line
			(start -0.67945 -0.3048)
			(end -0.67945 0.3048)
			(stroke
				(width 0.1)
				(type default)
			)
			(layer "B.Fab")
		)
		(fp_line
			(start -0.67945 0.3048)
			(end -0.120396 0.3048)
			(stroke
				(width 0.1)
				(type default)
			)
			(layer "B.Fab")
		)
		(fp_line
			(start -0.12065 -0.3048)
			(end -0.67945 -0.3048)
			(stroke
				(width 0.1)
				(type default)
			)
			(layer "B.Fab")
		)
		(fp_line
			(start -0.12065 -0.2794)
			(end -0.12065 -0.3048)
			(stroke
				(width 0.1)
				(type default)
			)
			(layer "B.Fab")
		)
		(fp_line
			(start -0.120396 0.2794)
			(end 0.12065 0.2794)
			(stroke
				(width 0.1)
				(type default)
			)
			(layer "B.Fab")
		)
		(fp_line
			(start -0.120396 0.3048)
			(end -0.120396 0.2794)
			(stroke
				(width 0.1)
				(type default)
			)
			(layer "B.Fab")
		)
		(fp_line
			(start 0.12065 -0.305054)
			(end 0.12065 -0.2794)
			(stroke
				(width 0.1)
				(type default)
			)
			(layer "B.Fab")
		)
		(fp_line
			(start 0.12065 -0.2794)
			(end -0.12065 -0.2794)
			(stroke
				(width 0.1)
				(type default)
			)
			(layer "B.Fab")
		)
		(fp_line
			(start 0.12065 0.2794)
			(end 0.12065 0.3048)
			(stroke
				(width 0.1)
				(type default)
			)
			(layer "B.Fab")
		)
		(fp_line
			(start 0.12065 0.3048)
			(end 0.67945 0.3048)
			(stroke
				(width 0.1)
				(type default)
			)
			(layer "B.Fab")
		)
		(fp_line
			(start 0.67945 -0.305054)
			(end 0.12065 -0.305054)
			(stroke
				(width 0.1)
				(type default)
			)
			(layer "B.Fab")
		)
		(fp_line
			(start 0.67945 0.3048)
			(end 0.67945 -0.305054)
			(stroke
				(width 0.1)
				(type default)
			)
			(layer "B.Fab")
		)
		(pad "1" smd circle
			(at 0.40005 0 180)
			(size 0 0)
			(layers "B.Cu" "B.Mask" "B.Paste")
			(net "HP_LVC3_OCP_V3_2_P12V_PWRGD")
		)
		(pad "2" smd circle
			(at -0.40005 0 180)
			(size 0 0)
			(layers "B.Cu" "B.Mask" "B.Paste")
			(net "P3V3_OCP_EN_2")
		)
	)
	(footprint ""
		(layer "B.Cu")
		(at 75.7936 -384.66268 180)
		(property "Reference" "R787"
			(at 0 0 0)
			(layer "B.SilkS")
			(hide yes)
			(effects
				(font
					(size 1.27 1.27)
				)
				(justify mirror)
			)
		)
		(property "Value" ""
			(at 0 0 0)
			(layer "B.Fab")
			(effects
				(font
					(size 1.27 1.27)
				)
				(justify mirror)
			)
		)
		(duplicate_pad_numbers_are_jumpers no)
		(fp_line
			(start 0.32512 0.175006)
			(end 0.32512 -0.175006)
			(stroke
				(width 0.1)
				(type default)
			)
			(layer "B.Fab")
		)
		(fp_line
			(start 0.32512 -0.175006)
			(end -0.32512 -0.175006)
			(stroke
				(width 0.1)
				(type default)
			)
			(layer "B.Fab")
		)
		(fp_line
			(start -0.32512 0.175006)
			(end 0.32512 0.175006)
			(stroke
				(width 0.1)
				(type default)
			)
			(layer "B.Fab")
		)
		(fp_line
			(start -0.32512 -0.175006)
			(end -0.32512 0.175006)
			(stroke
				(width 0.1)
				(type default)
			)
			(layer "B.Fab")
		)
		(pad "1" smd rect
			(at 0.2667 0)
			(size 0.3048 0.381)
			(layers "B.Cu" "B.Mask" "B.Paste")
			(net "TEST1_RT_CPU1_P1")
		)
		(pad "2" smd rect
			(at -0.2667 0 180)
			(size 0.3048 0.381)
			(layers "B.Cu" "B.Mask" "B.Paste")
			(net "GND")
		)
	)
	(footprint ""
		(layer "B.Cu")
		(at 36.040568 -193.9798)
		(property "Reference" "C148"
			(at 0 0 0)
			(layer "B.SilkS")
			(hide yes)
			(effects
				(font
					(size 1.27 1.27)
				)
				(justify mirror)
			)
		)
		(property "Value" ""
			(at 0 0 0)
			(layer "B.Fab")
			(effects
				(font
					(size 1.27 1.27)
				)
				(justify mirror)
			)
		)
		(duplicate_pad_numbers_are_jumpers no)
		(fp_line
			(start -0.7874 -0.4064)
			(end -0.7874 0.4064)
			(stroke
				(width 0.1524)
				(type default)
			)
			(layer "B.SilkS")
		)
		(fp_line
			(start -0.7874 0.4064)
			(end 0.7874 0.4064)
			(stroke
				(width 0.1524)
				(type default)
			)
			(layer "B.SilkS")
		)
		(fp_line
			(start 0.7874 -0.4064)
			(end -0.7874 -0.4064)
			(stroke
				(width 0.1524)
				(type default)
			)
			(layer "B.SilkS")
		)
		(fp_line
			(start 0.7874 0.4064)
			(end 0.7874 -0.4064)
			(stroke
				(width 0.1524)
				(type default)
			)
			(layer "B.SilkS")
		)
		(fp_line
			(start -0.67945 -0.3048)
			(end -0.67945 0.3048)
			(stroke
				(width 0.1)
				(type default)
			)
			(layer "B.Fab")
		)
		(fp_line
			(start -0.67945 0.3048)
			(end -0.120396 0.3048)
			(stroke
				(width 0.1)
				(type default)
			)
			(layer "B.Fab")
		)
		(fp_line
			(start -0.12065 -0.3048)
			(end -0.67945 -0.3048)
			(stroke
				(width 0.1)
				(type default)
			)
			(layer "B.Fab")
		)
		(fp_line
			(start -0.12065 -0.2794)
			(end -0.12065 -0.3048)
			(stroke
				(width 0.1)
				(type default)
			)
			(layer "B.Fab")
		)
		(fp_line
			(start -0.120396 0.2794)
			(end 0.12065 0.2794)
			(stroke
				(width 0.1)
				(type default)
			)
			(layer "B.Fab")
		)
		(fp_line
			(start -0.120396 0.3048)
			(end -0.120396 0.2794)
			(stroke
				(width 0.1)
				(type default)
			)
			(layer "B.Fab")
		)
		(fp_line
			(start 0.12065 -0.305054)
			(end 0.12065 -0.2794)
			(stroke
				(width 0.1)
				(type default)
			)
			(layer "B.Fab")
		)
		(fp_line
			(start 0.12065 -0.2794)
			(end -0.12065 -0.2794)
			(stroke
				(width 0.1)
				(type default)
			)
			(layer "B.Fab")
		)
		(fp_line
			(start 0.12065 0.2794)
			(end 0.12065 0.3048)
			(stroke
				(width 0.1)
				(type default)
			)
			(layer "B.Fab")
		)
		(fp_line
			(start 0.12065 0.3048)
			(end 0.67945 0.3048)
			(stroke
				(width 0.1)
				(type default)
			)
			(layer "B.Fab")
		)
		(fp_line
			(start 0.67945 -0.305054)
			(end 0.12065 -0.305054)
			(stroke
				(width 0.1)
				(type default)
			)
			(layer "B.Fab")
		)
		(fp_line
			(start 0.67945 0.3048)
			(end 0.67945 -0.305054)
			(stroke
				(width 0.1)
				(type default)
			)
			(layer "B.Fab")
		)
		(pad "1" smd circle
			(at 0.40005 0 180)
			(size 0 0)
			(layers "B.Cu" "B.Mask" "B.Paste")
			(net "P3V3_AUX")
		)
		(pad "2" smd circle
			(at -0.40005 0 180)
			(size 0 0)
			(layers "B.Cu" "B.Mask" "B.Paste")
			(net "GND")
		)
	)
)
